(kicad_pcb
	(version 20260206)
	(generator "pcbnew")
	(generator_version "10.0")
	(general
		(thickness 1.6)
		(legacy_teardrops no)
	)
	(paper "A4")
	(title_block
		(title "04192023_DAF0TMB3IC0_F0TG_MB_C_brd_V02_OCP.brd")
		(comment 1 "Grand Teton / footprints 3884-3887 of 8354")
	)
	(layers
		(0 "F.Cu" signal "TOP")
		(4 "In1.Cu" signal "GND")
		(6 "In2.Cu" signal "IN1")
		(8 "In3.Cu" signal "GND1")
		(10 "In4.Cu" signal "IN2")
		(12 "In5.Cu" signal "GND2")
		(14 "In6.Cu" signal "IN3")
		(16 "In7.Cu" signal "GND3")
		(18 "In8.Cu" signal "VCC")
		(20 "In9.Cu" signal "VCC1")
		(22 "In10.Cu" signal "GND4")
		(24 "In11.Cu" signal "IN4")
		(26 "In12.Cu" signal "GND5")
		(28 "In13.Cu" signal "IN5")
		(30 "In14.Cu" signal "GND6")
		(32 "In15.Cu" signal "IN6")
		(34 "In16.Cu" signal "GND7")
		(2 "B.Cu" signal "BOTTOM")
		(9 "F.Adhes" user "F.Adhesive")
		(11 "B.Adhes" user "B.Adhesive")
		(13 "F.Paste" user "Package Geometry/Pastemask Top")
		(15 "B.Paste" user "Package Geometry/Pastemask Bottom")
		(5 "F.SilkS" user "Ref Des/Silkscreen Top")
		(7 "B.SilkS" user "Ref Des/Silkscreen Bottom")
		(1 "F.Mask" user "Board Geometry/Soldermask Top")
		(3 "B.Mask" user "Board Geometry/Soldermask Bottom")
		(17 "Dwgs.User" user "User.Drawings")
		(19 "Cmts.User" user "User.Comments")
		(21 "Eco1.User" user "User.Eco1")
		(23 "Eco2.User" user "User.Eco2")
		(25 "Edge.Cuts" user "Board Geometry/Outline")
		(27 "Margin" user)
		(31 "F.CrtYd" user "Package Geometry/Place Bound Top")
		(29 "B.CrtYd" user "Package Geometry/Place Bound Bottom")
		(35 "F.Fab" user "Ref Des/Assembly Top")
		(33 "B.Fab" user "Ref Des/Assembly Bottom")
	)
	(footprint ""
		(layer "F.Cu")
		(at 102.354126 -412.578296 90)
		(property "Reference" "R6862"
			(at 0 0 90)
			(layer "F.SilkS")
			(hide yes)
			(effects
				(font
					(size 1.27 1.27)
				)
			)
		)
		(property "Value" ""
			(at 0 0 90)
			(layer "F.Fab")
			(effects
				(font
					(size 1.27 1.27)
				)
			)
		)
		(duplicate_pad_numbers_are_jumpers no)
		(fp_line
			(start 0.7874 -0.4064)
			(end 0.7874 0.4064)
			(stroke
				(width 0.1524)
				(type default)
			)
			(layer "F.SilkS")
		)
		(fp_line
			(start -0.7874 -0.4064)
			(end 0.7874 -0.4064)
			(stroke
				(width 0.1524)
				(type default)
			)
			(layer "F.SilkS")
		)
		(fp_line
			(start 0.7874 0.4064)
			(end -0.7874 0.4064)
			(stroke
				(width 0.1524)
				(type default)
			)
			(layer "F.SilkS")
		)
		(fp_line
			(start -0.7874 0.4064)
			(end -0.7874 -0.4064)
			(stroke
				(width 0.1524)
				(type default)
			)
			(layer "F.SilkS")
		)
		(fp_line
			(start -0.12065 -0.305054)
			(end -0.12065 -0.2794)
			(stroke
				(width 0.1)
				(type default)
			)
			(layer "F.Fab")
		)
		(fp_line
			(start -0.67945 -0.305054)
			(end -0.12065 -0.305054)
			(stroke
				(width 0.1)
				(type default)
			)
			(layer "F.Fab")
		)
		(fp_line
			(start 0.67945 -0.3048)
			(end 0.67945 0.3048)
			(stroke
				(width 0.1)
				(type default)
			)
			(layer "F.Fab")
		)
		(fp_line
			(start 0.12065 -0.3048)
			(end 0.67945 -0.3048)
			(stroke
				(width 0.1)
				(type default)
			)
			(layer "F.Fab")
		)
		(fp_line
			(start 0.12065 -0.2794)
			(end 0.12065 -0.3048)
			(stroke
				(width 0.1)
				(type default)
			)
			(layer "F.Fab")
		)
		(fp_line
			(start -0.12065 -0.2794)
			(end 0.12065 -0.2794)
			(stroke
				(width 0.1)
				(type default)
			)
			(layer "F.Fab")
		)
		(fp_line
			(start 0.120396 0.2794)
			(end -0.12065 0.2794)
			(stroke
				(width 0.1)
				(type default)
			)
			(layer "F.Fab")
		)
		(fp_line
			(start -0.12065 0.2794)
			(end -0.12065 0.3048)
			(stroke
				(width 0.1)
				(type default)
			)
			(layer "F.Fab")
		)
		(fp_line
			(start 0.67945 0.3048)
			(end 0.120396 0.3048)
			(stroke
				(width 0.1)
				(type default)
			)
			(layer "F.Fab")
		)
		(fp_line
			(start 0.120396 0.3048)
			(end 0.120396 0.2794)
			(stroke
				(width 0.1)
				(type default)
			)
			(layer "F.Fab")
		)
		(fp_line
			(start -0.12065 0.3048)
			(end -0.67945 0.3048)
			(stroke
				(width 0.1)
				(type default)
			)
			(layer "F.Fab")
		)
		(fp_line
			(start -0.67945 0.3048)
			(end -0.67945 -0.305054)
			(stroke
				(width 0.1)
				(type default)
			)
			(layer "F.Fab")
		)
		(pad "1" smd circle
			(at -0.40005 0 90)
			(size 0 0)
			(layers "F.Cu" "F.Mask" "F.Paste")
			(net "SMB_HOST_CLK_3V3AUX_SCL_R1")
		)
		(pad "2" smd circle
			(at 0.40005 0 90)
			(size 0 0)
			(layers "F.Cu" "F.Mask" "F.Paste")
			(net "SMB_9ZXL045_P1_SCL")
		)
	)
	(footprint ""
		(layer "F.Cu")
		(at 43.543982 -386.684774 -90)
		(property "Reference" "R627"
			(at 0 0 270)
			(layer "F.SilkS")
			(hide yes)
			(effects
				(font
					(size 1.27 1.27)
				)
			)
		)
		(property "Value" ""
			(at 0 0 270)
			(layer "F.Fab")
			(effects
				(font
					(size 1.27 1.27)
				)
			)
		)
		(duplicate_pad_numbers_are_jumpers no)
		(fp_line
			(start -0.32512 0.175006)
			(end -0.32512 -0.175006)
			(stroke
				(width 0.1)
				(type default)
			)
			(layer "F.Fab")
		)
		(fp_line
			(start 0.32512 0.175006)
			(end -0.32512 0.175006)
			(stroke
				(width 0.1)
				(type default)
			)
			(layer "F.Fab")
		)
		(fp_line
			(start -0.32512 -0.175006)
			(end 0.32512 -0.175006)
			(stroke
				(width 0.1)
				(type default)
			)
			(layer "F.Fab")
		)
		(fp_line
			(start 0.32512 -0.175006)
			(end 0.32512 0.175006)
			(stroke
				(width 0.1)
				(type default)
			)
			(layer "F.Fab")
		)
		(pad "1" smd rect
			(at -0.2667 0 270)
			(size 0.3048 0.381)
			(layers "F.Cu" "F.Mask" "F.Paste")
			(net "CLK_100M_RETIMER_CPU1_P0_DN")
		)
		(pad "2" smd rect
			(at 0.2667 0 90)
			(size 0.3048 0.381)
			(layers "F.Cu" "F.Mask" "F.Paste")
			(net "GND")
		)
	)
	(footprint ""
		(layer "F.Cu")
		(at 14.064996 -99.136454 -90)
		(property "Reference" "U268"
			(at -3.448304 -3.957828 0)
			(unlocked yes)
			(layer "F.SilkS")
			(effects
				(font
					(size 0.7874 0.5842)
					(thickness 0.1524)
				)
				(justify left)
			)
		)
		(property "Value" ""
			(at 0 0 270)
			(layer "F.Fab")
			(effects
				(font
					(size 1.27 1.27)
				)
			)
		)
		(duplicate_pad_numbers_are_jumpers no)
		(fp_line
			(start -0.508 2.921)
			(end -0.508 3.683)
			(stroke
				(width 0.1524)
				(type default)
			)
			(layer "F.SilkS")
		)
		(fp_line
			(start -2.500122 2.500122)
			(end -2.500122 1.778)
			(stroke
				(width 0.1524)
				(type default)
			)
			(layer "F.SilkS")
		)
		(fp_line
			(start -1.778 2.500122)
			(end -2.500122 2.500122)
			(stroke
				(width 0.1524)
				(type default)
			)
			(layer "F.SilkS")
		)
		(fp_line
			(start 2.500122 2.500122)
			(end 1.778 2.500122)
			(stroke
				(width 0.1524)
				(type default)
			)
			(layer "F.SilkS")
		)
		(fp_line
			(start 2.500122 1.778)
			(end 2.500122 2.500122)
			(stroke
				(width 0.1524)
				(type default)
			)
			(layer "F.SilkS")
		)
		(fp_line
			(start 2.921 1.524)
			(end 3.302 1.524)
			(stroke
				(width 0.1524)
				(type default)
			)
			(layer "F.SilkS")
		)
		(fp_line
			(start -2.921 0.508)
			(end -3.302 0.508)
			(stroke
				(width 0.1524)
				(type default)
			)
			(layer "F.SilkS")
		)
		(fp_line
			(start 2.921 -1.016)
			(end 3.683 -1.016)
			(stroke
				(width 0.1524)
				(type default)
			)
			(layer "F.SilkS")
		)
		(fp_line
			(start -2.500122 -1.778)
			(end -2.500122 -2.500122)
			(stroke
				(width 0.1524)
				(type default)
			)
			(layer "F.SilkS")
		)
		(fp_line
			(start -2.500122 -2.500122)
			(end -1.778 -2.500122)
			(stroke
				(width 0.1524)
				(type default)
			)
			(layer "F.SilkS")
		)
		(fp_line
			(start 1.778 -2.500122)
			(end 2.500122 -2.500122)
			(stroke
				(width 0.1524)
				(type default)
			)
			(layer "F.SilkS")
		)
		(fp_line
			(start 2.500122 -2.500122)
			(end 2.500122 -1.778)
			(stroke
				(width 0.1524)
				(type default)
			)
			(layer "F.SilkS")
		)
		(fp_line
			(start 0 -2.921)
			(end 0 -3.302)
			(stroke
				(width 0.1524)
				(type default)
			)
			(layer "F.SilkS")
		)
		(fp_poly
			(pts
				(xy -3.016504 -2.991358) (xy -2.71018 -2.07264) (xy -3.629152 -2.37871)
			)
			(stroke
				(width 0)
				(type default)
			)
			(fill yes)
			(layer "F.SilkS")
		)
		(fp_line
			(start -0.508 2.921)
			(end -0.508 3.683)
			(stroke
				(width 0.1)
				(type default)
			)
			(layer "F.Fab")
		)
		(fp_line
			(start -2.500122 2.500122)
			(end -2.500122 -2.500122)
			(stroke
				(width 0.1)
				(type default)
			)
			(layer "F.Fab")
		)
		(fp_line
			(start 2.500122 2.500122)
			(end -2.500122 2.500122)
			(stroke
				(width 0.1)
				(type default)
			)
			(layer "F.Fab")
		)
		(fp_line
			(start 2.921 1.524)
			(end 3.302 1.524)
			(stroke
				(width 0.1)
				(type default)
			)
			(layer "F.Fab")
		)
		(fp_line
			(start -2.921 0.508)
			(end -3.302 0.508)
			(stroke
				(width 0.1)
				(type default)
			)
			(layer "F.Fab")
		)
		(fp_line
			(start 2.921 -1.016)
			(end 3.683 -1.016)
			(stroke
				(width 0.1)
				(type default)
			)
			(layer "F.Fab")
		)
		(fp_line
			(start -2.500122 -2.500122)
			(end 2.500122 -2.500122)
			(stroke
				(width 0.1)
				(type default)
			)
			(layer "F.Fab")
		)
		(fp_line
			(start 2.500122 -2.500122)
			(end 2.500122 2.500122)
			(stroke
				(width 0.1)
				(type default)
			)
			(layer "F.Fab")
		)
		(fp_line
			(start 0 -2.921)
			(end 0 -3.302)
			(stroke
				(width 0.1)
				(type default)
			)
			(layer "F.Fab")
		)
		(fp_poly
			(pts
				(xy -3.7592 -1.933194) (xy -2.892806 -1.500124) (xy -3.7592 -1.0668)
			)
			(stroke
				(width 0)
				(type default)
			)
			(fill yes)
			(layer "F.Fab")
		)
		(fp_text user "15"
			(at 4.098036 4.054856 0)
			(unlocked yes)
			(layer "F.SilkS")
			(effects
				(font
					(size 0.635 0.4064)
					(thickness 0.1524)
				)
			)
		)
		(fp_text user "14"
			(at 1.306576 3.310636 0)
			(unlocked yes)
			(layer "F.SilkS")
			(effects
				(font
					(size 0.635 0.4064)
					(thickness 0.1524)
				)
			)
		)
		(fp_text user "8"
			(at -2.064004 2.993136 0)
			(unlocked yes)
			(layer "F.SilkS")
			(effects
				(font
					(size 0.635 0.4064)
					(thickness 0.1524)
				)
			)
		)
		(fp_text user "7"
			(at -3.147568 1.8034 0)
			(unlocked yes)
			(layer "F.SilkS")
			(effects
				(font
					(size 0.635 0.4064)
					(thickness 0.1524)
				)
			)
		)
		(fp_text user "21"
			(at 4.557776 -3.974084 0)
			(unlocked yes)
			(layer "F.SilkS")
			(effects
				(font
					(size 0.635 0.4064)
					(thickness 0.1524)
				)
			)
		)
		(fp_text user "28"
			(at -1.357884 -4.0513 0)
			(unlocked yes)
			(layer "F.SilkS")
			(effects
				(font
					(size 0.635 0.4064)
					(thickness 0.1524)
				)
			)
		)
		(fp_text user "22"
			(at 3.315716 -4.591304 0)
			(unlocked yes)
			(layer "F.SilkS")
			(effects
				(font
					(size 0.635 0.4064)
					(thickness 0.1524)
				)
			)
		)
		(fp_text user "8"
			(at -1.8796 3.253232 270)
			(unlocked yes)
			(layer "F.Fab")
			(effects
				(font
					(size 0.635 0.4064)
					(thickness 0.1524)
				)
			)
		)
		(fp_text user "14"
			(at 2.1336 3.253232 270)
			(unlocked yes)
			(layer "F.Fab")
			(effects
				(font
					(size 0.635 0.4064)
					(thickness 0.1524)
				)
			)
		)
		(fp_text user "15"
			(at 3.253232 2.2352 0)
			(unlocked yes)
			(layer "F.Fab")
			(effects
				(font
					(size 0.635 0.4064)
					(thickness 0.1524)
				)
			)
		)
		(fp_text user "7"
			(at -3.147568 1.8034 0)
			(unlocked yes)
			(layer "F.Fab")
			(effects
				(font
					(size 0.635 0.4064)
					(thickness 0.1524)
				)
			)
		)
		(fp_text user "21"
			(at 3.227832 -2.2606 0)
			(unlocked yes)
			(layer "F.Fab")
			(effects
				(font
					(size 0.635 0.4064)
					(thickness 0.1524)
				)
			)
		)
		(fp_text user "28"
			(at -2.2098 -3.172968 270)
			(unlocked yes)
			(layer "F.Fab")
			(effects
				(font
					(size 0.635 0.4064)
					(thickness 0.1524)
				)
			)
		)
		(fp_text user "22"
			(at 2.2352 -3.172968 270)
			(unlocked yes)
			(layer "F.Fab")
			(effects
				(font
					(size 0.635 0.4064)
					(thickness 0.1524)
				)
			)
		)
		(pad "1" smd rect
			(at -2.412492 -1.500124)
			(size 0.254 0.7366)
			(layers "F.Cu" "F.Mask" "F.Paste")
			(net "USB2_P0_R_DN")
		)
		(pad "2" smd rect
			(at -2.412492 -0.999998)
			(size 0.254 0.7366)
			(layers "F.Cu" "F.Mask" "F.Paste")
			(net "USB2_P0_R_DP")
		)
		(pad "3" smd rect
			(at -2.412492 -0.499872)
			(size 0.254 0.7366)
			(layers "F.Cu" "F.Mask" "F.Paste")
			(net "USB2_HUB_SWB_DN")
		)
		(pad "4" smd rect
			(at -2.412492 0)
			(size 0.254 0.7366)
			(layers "F.Cu" "F.Mask" "F.Paste")
			(net "USB2_HUB_SWB_DP")
		)
		(pad "5" smd rect
			(at -2.412492 0.499872)
			(size 0.254 0.7366)
			(layers "F.Cu" "F.Mask" "F.Paste")
			(net "P3V3_AUX_USB_HUB")
		)
		(pad "6" smd rect
			(at -2.412492 0.999998)
			(size 0.254 0.7366)
			(layers "F.Cu" "F.Mask" "F.Paste")
			(net "NC_USB_HUB_DM2")
		)
		(pad "7" smd rect
			(at -2.412492 1.500124)
			(size 0.254 0.7366)
			(layers "F.Cu" "F.Mask" "F.Paste")
			(net "NC_USB_HUB_DP2")
		)
		(pad "8" smd rect
			(at -1.500124 2.412492 270)
			(size 0.254 0.7366)
			(layers "F.Cu" "F.Mask" "F.Paste")
			(net "USB_HUB_RREF")
		)
		(pad "9" smd rect
			(at -0.999998 2.412492 270)
			(size 0.254 0.7366)
			(layers "F.Cu" "F.Mask" "F.Paste")
			(net "P3V3_AUX_USB_HUB")
		)
		(pad "10" smd rect
			(at -0.499872 2.412492 270)
			(size 0.254 0.7366)
			(layers "F.Cu" "F.Mask" "F.Paste")
			(net "USB_HUB_XTAL_IN")
		)
		(pad "11" smd rect
			(at 0 2.412492 270)
			(size 0.254 0.7366)
			(layers "F.Cu" "F.Mask" "F.Paste")
			(net "USB_HUB_XTAL_OUT")
		)
		(pad "12" smd rect
			(at 0.499872 2.412492 270)
			(size 0.254 0.7366)
			(layers "F.Cu" "F.Mask" "F.Paste")
			(net "NC_USB_HUB_DM3")
		)
		(pad "13" smd rect
			(at 0.999998 2.412492 270)
			(size 0.254 0.7366)
			(layers "F.Cu" "F.Mask" "F.Paste")
			(net "NC_USB_HUB_DP3")
		)
		(pad "14" smd rect
			(at 1.500124 2.412492 270)
			(size 0.254 0.7366)
			(layers "F.Cu" "F.Mask" "F.Paste")
			(net "P3V3_AUX_USB_HUB")
		)
		(pad "15" smd rect
			(at 2.412492 1.500124)
			(size 0.254 0.7366)
			(layers "F.Cu" "F.Mask" "F.Paste")
			(net "NC_USB_HUB_DM4")
		)
		(pad "16" smd rect
			(at 2.412492 0.999998)
			(size 0.254 0.7366)
			(layers "F.Cu" "F.Mask" "F.Paste")
			(net "NC_USB_HUB_DP4")
		)
		(pad "17" smd rect
			(at 2.412492 0.499872)
			(size 0.254 0.7366)
			(layers "F.Cu" "F.Mask" "F.Paste")
			(net "RST_USB_HUB_R_N")
		)
		(pad "18" smd rect
			(at 2.412492 0)
			(size 0.254 0.7366)
			(layers "F.Cu" "F.Mask" "F.Paste")
			(net "USB_HUB_TEST")
		)
		(pad "19" smd rect
			(at 2.412492 -0.499872)
			(size 0.254 0.7366)
			(layers "F.Cu" "F.Mask" "F.Paste")
			(net "USB_HUB_OVCUR4")
		)
		(pad "20" smd rect
			(at 2.412492 -0.999998)
			(size 0.254 0.7366)
			(layers "F.Cu" "F.Mask" "F.Paste")
			(net "USB_HUB_OVCUR3")
		)
		(pad "21" smd rect
			(at 2.412492 -1.500124)
			(size 0.254 0.7366)
			(layers "F.Cu" "F.Mask" "F.Paste")
			(net "USB_HUB_DVDD")
		)
		(pad "22" smd rect
			(at 1.500124 -2.412492 270)
			(size 0.254 0.7366)
			(layers "F.Cu" "F.Mask" "F.Paste")
			(net "USB_HUB_PSELF")
		)
		(pad "23" smd rect
			(at 0.999998 -2.412492 270)
			(size 0.254 0.7366)
			(layers "F.Cu" "F.Mask" "F.Paste")
			(net "USB_HUB_PGANG")
		)
		(pad "24" smd rect
			(at 0.499872 -2.412492 270)
			(size 0.254 0.7366)
			(layers "F.Cu" "F.Mask" "F.Paste")
			(net "USB_HUB_OVCUR2")
		)
		(pad "25" smd rect
			(at 0 -2.412492 270)
			(size 0.254 0.7366)
			(layers "F.Cu" "F.Mask" "F.Paste")
			(net "USB_HUB_OVCUR1")
		)
		(pad "26" smd rect
			(at -0.499872 -2.412492 270)
			(size 0.254 0.7366)
			(layers "F.Cu" "F.Mask" "F.Paste")
			(net "NC_USB_HUB_SDA")
		)
		(pad "27" smd rect
			(at -0.999998 -2.412492 270)
			(size 0.254 0.7366)
			(layers "F.Cu" "F.Mask" "F.Paste")
			(net "P3V3_AUX_USB_HUB")
		)
		(pad "28" smd rect
			(at -1.500124 -2.412492 270)
			(size 0.254 0.7366)
			(layers "F.Cu" "F.Mask" "F.Paste")
			(net "P3V3_AUX_USB_HUB")
		)
		(pad "TH" smd rect
			(at 0 0 270)
			(size 3.556 3.556)
			(layers "F.Cu" "F.Mask" "F.Paste")
			(net "GND")
		)
		(zone
			(layer "F.Cu")
			(hatch none 0.5)
			(connect_pads
				(clearance 0)
			)
			(min_thickness 0.25)
			(keepout
				(tracks not_allowed)
				(vias allowed)
				(pads allowed)
				(copperpour not_allowed)
				(footprints allowed)
			)
			(placement
				(enabled no)
				(sheetname "")
			)
			(fill
				(thermal_gap 0.5)
				(thermal_bridge_width 0.5)
				(island_removal_mode 0)
			)
			(polygon
				(pts
					(xy 16.046196 -98.196654) (xy 15.893796 -98.196654) (xy 15.893796 -100.965254) (xy 12.236196 -100.965254)
					(xy 12.236196 -97.307654) (xy 15.893796 -97.307654) (xy 15.893796 -98.171254) (xy 16.046196 -98.171254)
					(xy 16.046196 -97.155254) (xy 12.083796 -97.155254) (xy 12.083796 -101.117654) (xy 16.046196 -101.117654)
				)
			)
		)
	)
	(footprint ""
		(layer "F.Cu")
		(at 85.322156 -41.95318)
		(property "Reference" "C1821"
			(at 0 0 0)
			(layer "F.SilkS")
			(hide yes)
			(effects
				(font
					(size 1.27 1.27)
				)
			)
		)
		(property "Value" ""
			(at 0 0 0)
			(layer "F.Fab")
			(effects
				(font
					(size 1.27 1.27)
				)
			)
		)
		(duplicate_pad_numbers_are_jumpers no)
		(fp_line
			(start -0.7874 -0.4064)
			(end 0.7874 -0.4064)
			(stroke
				(width 0.1524)
				(type default)
			)
			(layer "F.SilkS")
		)
		(fp_line
			(start -0.7874 0.4064)
			(end -0.7874 -0.4064)
			(stroke
				(width 0.1524)
				(type default)
			)
			(layer "F.SilkS")
		)
		(fp_line
			(start 0.7874 -0.4064)
			(end 0.7874 0.4064)
			(stroke
				(width 0.1524)
				(type default)
			)
			(layer "F.SilkS")
		)
		(fp_line
			(start 0.7874 0.4064)
			(end -0.7874 0.4064)
			(stroke
				(width 0.1524)
				(type default)
			)
			(layer "F.SilkS")
		)
		(fp_line
			(start -0.67945 -0.305054)
			(end -0.12065 -0.305054)
			(stroke
				(width 0.1)
				(type default)
			)
			(layer "F.Fab")
		)
		(fp_line
			(start -0.67945 0.3048)
			(end -0.67945 -0.305054)
			(stroke
				(width 0.1)
				(type default)
			)
			(layer "F.Fab")
		)
		(fp_line
			(start -0.12065 -0.305054)
			(end -0.12065 -0.2794)
			(stroke
				(width 0.1)
				(type default)
			)
			(layer "F.Fab")
		)
		(fp_line
			(start -0.12065 -0.2794)
			(end 0.12065 -0.2794)
			(stroke
				(width 0.1)
				(type default)
			)
			(layer "F.Fab")
		)
		(fp_line
			(start -0.12065 0.2794)
			(end -0.12065 0.3048)
			(stroke
				(width 0.1)
				(type default)
			)
			(layer "F.Fab")
		)
		(fp_line
			(start -0.12065 0.3048)
			(end -0.67945 0.3048)
			(stroke
				(width 0.1)
				(type default)
			)
			(layer "F.Fab")
		)
		(fp_line
			(start 0.120396 0.2794)
			(end -0.12065 0.2794)
			(stroke
				(width 0.1)
				(type default)
			)
			(layer "F.Fab")
		)
		(fp_line
			(start 0.120396 0.3048)
			(end 0.120396 0.2794)
			(stroke
				(width 0.1)
				(type default)
			)
			(layer "F.Fab")
		)
		(fp_line
			(start 0.12065 -0.3048)
			(end 0.67945 -0.3048)
			(stroke
				(width 0.1)
				(type default)
			)
			(layer "F.Fab")
		)
		(fp_line
			(start 0.12065 -0.2794)
			(end 0.12065 -0.3048)
			(stroke
				(width 0.1)
				(type default)
			)
			(layer "F.Fab")
		)
		(fp_line
			(start 0.67945 -0.3048)
			(end 0.67945 0.3048)
			(stroke
				(width 0.1)
				(type default)
			)
			(layer "F.Fab")
		)
		(fp_line
			(start 0.67945 0.3048)
			(end 0.120396 0.3048)
			(stroke
				(width 0.1)
				(type default)
			)
			(layer "F.Fab")
		)
		(pad "1" smd circle
			(at -0.40005 0)
			(size 0 0)
			(layers "F.Cu" "F.Mask" "F.Paste")
			(net "P3V3_AUX")
		)
		(pad "2" smd circle
			(at 0.40005 0)
			(size 0 0)
			(layers "F.Cu" "F.Mask" "F.Paste")
			(net "GND")
		)
	)
)
